FILE_TYPE = CONNECTIVITY;
{Allegro Design Entry HDL 16.6-p007 (v16-6-112F) 10/10/2012}
"PAGE_NUMBER" = 228;
0"NC";
1"PVDDQ_KLM\g";
2"GND\g";
3"VR_FET_SW_P12V_STBY_PVDDQ_KLM\g";
4"GND\g";
5"P12V_STBY\g";
6"GND\g";
7"PVDDQ_KLM\g";
8"PVDDQ_KLM\g";
9"GND\g";
10"PVDDQ_KLM\g";
11"GND\g";
12"PVDDQ_KLM\g";
13"GND\g";
14"PVDDQ_KLM\g";
15"GND\g";
16"GND\g";
17"PVDDQ_KLM\g";
18"PVDDQ_KLM\g";
19"GND\g";
20"PVDDQ_KLM\g";
21"GND\g";
22"VSENSE_PVDDQ_KLM_P";
23"VSENSE_PVDDQ_KLM_N";
%"PVDDQ_KLM"
"1","(2525,1700)","0","mstr_symbols","I109";
;
HDL_POWER"PVDDQ_KLM"
BODY_TYPE"PLUMBING"
BOM_COST"MEM_VRD_PVDDQ_CD"
ROOM"VDDQ_KLM_PWR_VR"
CDS_LIB"mstr_symbols"
VOLTAGE"1.2V";
"G\NAC"1;
%"CAP"
"1","(2400,2825)","0","mstr_discrete","I110";
;
CDS_SEC"1"
ROOM"VDDQ_KLM_PWR_VR"
BOM_COST"MEM_VRD_PVDDQ_CD"
SEC_TYPE"0805"
SEC"1"
CDS_LOCATION"C8L1"
CDS_LIB"mstr_discrete"
PACK_TYPE"0805"
VALUE"100UF"
PART_NUMBER"602433-112"
LOCATION"C8L1"
VOLTAGE"4V"
TOLERANCE"20%"
MATERIAL"X5R";
"A"
$PN"1"20;
"B"
$PN"2"21;
%"GND"
"1","(4250,1050)","0","mstr_symbols","I114";
;
HDL_POWER"GND"
BODY_TYPE"PLUMBING"
VOLTAGE"0"
CDS_LIB"mstr_symbols"
SIZE"1B"
BOM_COST"MEM_VRD_PVDDQ_CD"
ROOM"VDDQ_KLM_PWR_VR";
"A\NAC"2;
%"VCC_CORE"
"1","(-675,1350)","0","mstr_symbols","I120";
;
CDS_LIB"mstr_symbols"
HDL_POWER"VR_FET_SW_P12V_STBY_PVDDQ_KLM";
"A"3;
%"GND"
"1","(-675,675)","0","mstr_symbols","I123";
;
HDL_POWER"GND"
BODY_TYPE"PLUMBING"
CDS_LIB"mstr_symbols"
SIZE"1B"
VOLTAGE"0"
BOM_COST"MEM_VRD_PVDDQ_CD"
ROOM"VDDQ_KLM_PWR_VR";
"A\NAC"4;
%"INDUCTOR"
"1","(-1100,1100)","0","mstr_discrete","I124";
;
CDS_SEC"1"
SEC"1"
SEC_TYPE"SM"
ROOM"VDDQ_KLM_PWR_VR"
BOM_COST"MEM_VRD_PVDDQ_CD"
CDS_LIB"mstr_discrete"
CDS_LOCATION"L1B1"
PACK_TYPE"SM"
MATERIAL"IND"
PART_NUMBER"D92183-020"
LOCATION"L1B1"
VALUE"100NH";
"INA\NAC"
$PN"1"5;
"INB\NAC"
$PN"2"3;
%"CAPP"
"1","(-675,900)","0","mstr_discrete","I175";
;
CDS_SEC"1"
SEC_TYPE"2626"
SEC"1"
ROOM"VDDQ_KLM_PWR_VR"
CDS_LOCATION"C1B10"
CDS_LIB"mstr_discrete"
LOCATION"C1B10"
MATERIAL"OSCON"
PACK_TYPE"2626"
VALUE"270UF"
PART_NUMBER"A31228-047"
VOLTAGE"16V"
TOLERANCE"20%";
"B"
$PN"2"4;
"A"
$PN"1"3;
%"P12V_STBY"
"1","(-1400,1375)","0","mstr_symbols","I182";
;
HDL_POWER"P12V_STBY"
BODY_TYPE"PLUMBING"
SIZE"1B"
CDS_LIB"mstr_symbols"
VOLTAGE"12.0V";
"G\NAC"5;
%"CAP"
"1","(-2300,2900)","0","mstr_discrete","I183";
;
CDS_SEC"1"
SEC_TYPE"0805LF"
SEC"1"
ROOM"VDDQ_KLM_CPU1"
BOM_COST"MEM_VRD_PVDDQ_KLM"
VOLTAGE"4V"
CDS_LIB"mstr_discrete"
CDS_LOCATION"C8P2"
LOCATION"C8P2"
VALUE"22UF"
PART_NUMBER"C95333-002"
TOLERANCE"20%"
MATERIAL"X6S"
PACK_TYPE"0805LF";
"A"
$PN"1"7;
"B"
$PN"2"11;
%"CAP"
"1","(-1900,2900)","0","mstr_discrete","I185";
;
CDS_SEC"1"
SEC"1"
SEC_TYPE"0805LF"
ROOM"VDDQ_KLM_CPU1"
BOM_COST"MEM_VRD_PVDDQ_KLM"
VOLTAGE"4V"
CDS_LIB"mstr_discrete"
CDS_LOCATION"C8P1"
PART_NUMBER"C95333-002"
MATERIAL"X6S"
PACK_TYPE"0805LF"
TOLERANCE"20%"
VALUE"22UF"
LOCATION"C8P1";
"A"
$PN"1"7;
"B"
$PN"2"11;
%"CAP"
"1","(-1550,2900)","0","mstr_discrete","I186";
;
CDS_SEC"1"
SEC"1"
SEC_TYPE"0603LF"
ROOM"VDDQ_KLM_CPU1"
BOM_COST"MEM_VRD_PVDDQ_KLM"
CDS_LOCATION"C2D7"
CDS_LIB"mstr_discrete"
PART_NUMBER"E15431-001"
MATERIAL"X6S"
VOLTAGE"4V"
PACK_TYPE"0603LF"
TOLERANCE"20%"
VALUE"10UF"
LOCATION"C2D7";
"A"
$PN"1"10;
"B"
$PN"2"6;
%"CAP"
"1","(-1200,2900)","0","mstr_discrete","I187";
;
CDS_SEC"1"
SEC"1"
SEC_TYPE"0603LF"
ROOM"VDDQ_KLM_CPU1"
BOM_COST"MEM_VRD_PVDDQ_KLM"
CDS_LOCATION"C2D4"
CDS_LIB"mstr_discrete"
PACK_TYPE"0603LF"
PART_NUMBER"E15431-001"
LOCATION"C2D4"
VALUE"10UF"
TOLERANCE"20%"
VOLTAGE"4V"
MATERIAL"X6S";
"A"
$PN"1"10;
"B"
$PN"2"6;
%"CAP"
"1","(-850,2900)","0","mstr_discrete","I188";
;
CDS_SEC"1"
SEC"1"
SEC_TYPE"0603LF"
ROOM"VDDQ_KLM_CPU1"
BOM_COST"MEM_VRD_PVDDQ_KLM"
CDS_LIB"mstr_discrete"
CDS_LOCATION"C2D5"
PART_NUMBER"E15431-001"
MATERIAL"X6S"
VOLTAGE"4V"
PACK_TYPE"0603LF"
TOLERANCE"20%"
VALUE"10UF"
LOCATION"C2D5";
"A"
$PN"1"10;
"B"
$PN"2"6;
%"GND"
"1","(-500,2525)","0","mstr_symbols","I189";
;
HDL_POWER"GND"
BODY_TYPE"PLUMBING"
CDS_LIB"mstr_symbols"
VOLTAGE"0"
SIZE"1B"
BOM_COST"MEM_VRD_PVDDQ_CD"
ROOM"VDDQ_ABC_PWR_VR";
"A\NAC"6;
%"CAP"
"1","(-500,2900)","0","mstr_discrete","I190";
;
CDS_SEC"1"
SEC"1"
SEC_TYPE"0603LF"
ROOM"VDDQ_KLM_CPU1"
BOM_COST"MEM_VRD_PVDDQ_KLM"
CDS_LOCATION"C2D6"
CDS_LIB"mstr_discrete"
PART_NUMBER"E15431-001"
VOLTAGE"4V"
TOLERANCE"20%"
VALUE"10UF"
LOCATION"C2D6"
MATERIAL"X6S"
PACK_TYPE"0603LF";
"A"
$PN"1"10;
"B"
$PN"2"6;
%"PVDDQ_KLM"
"1","(-2300,3175)","0","mstr_symbols","I191";
;
HDL_POWER"PVDDQ_KLM"
BODY_TYPE"PLUMBING"
ROOM"VDDQ_KLM_PWR_VR"
BOM_COST"MEM_VRD_PVPP_AB"
CDS_LIB"mstr_symbols"
VOLTAGE"1.2V";
"G\NAC"7;
%"PVDDQ_KLM"
"1","(2550,1000)","0","mstr_symbols","I195";
;
HDL_POWER"PVDDQ_KLM"
BODY_TYPE"PLUMBING"
ROOM"VDDQ_KLM_PWR_VR"
BOM_COST"MEM_VRD_PVDDQ_CD"
CDS_LIB"mstr_symbols"
VOLTAGE"1.2V";
"G\NAC"8;
%"GND"
"1","(3300,325)","0","mstr_symbols","I197";
;
HDL_POWER"GND"
BODY_TYPE"PLUMBING"
SIZE"1B"
CDS_LIB"mstr_symbols"
VOLTAGE"0"
ROOM"VDDQ_KLM_PWR_VR"
BOM_COST"MEM_VRD_PVDDQ_CD";
"A\NAC"9;
%"CAP_A"
"1","(2550,725)","0","dev_discrete","I198";
;
SEC"1"
SEC_TYPE"0603V"
CDS_SEC"1"
CDS_LOCATION"C8M8"
CDS_LIB"dev_discrete"
PART_NUMBER"602433-106"
MATERIAL"X5R"
VOLTAGE"4V"
PACK_TYPE"0603V"
TOLERANCE"20%"
VALUE"47UF"
LOCATION"C8M8";
"B"
$PN"2"9;
"A"
$PN"1"8;
%"CAP_A"
"1","(2900,725)","0","dev_discrete","I199";
;
CDS_LOCATION"C2A5"
CDS_SEC"1"
SEC_TYPE"0603V"
SEC"1"
CDS_LIB"dev_discrete"
PACK_TYPE"0603V"
PART_NUMBER"602433-106"
VALUE"47UF"
LOCATION"C2A5"
TOLERANCE"20%"
VOLTAGE"4V"
MATERIAL"X5R";
"B"
$PN"2"9;
"A"
$PN"1"8;
%"CAP_A"
"1","(3300,725)","0","dev_discrete","I200";
;
SEC"1"
SEC_TYPE"0603V"
CDS_SEC"1"
CDS_LOCATION"C2B1"
CDS_LIB"dev_discrete"
PART_NUMBER"602433-106"
LOCATION"C2B1"
VALUE"47UF"
TOLERANCE"20%"
PACK_TYPE"0603V"
VOLTAGE"4V"
MATERIAL"X5R";
"B"
$PN"2"9;
"A"
$PN"1"8;
%"CAP_A"
"1","(2525,1425)","0","dev_discrete","I201";
;
CDS_SEC"1"
SEC_TYPE"0603V"
SEC"1"
CDS_LOCATION"C8L12"
CDS_LIB"dev_discrete"
LOCATION"C8L12"
PART_NUMBER"602433-106"
MATERIAL"X5R"
VOLTAGE"4V"
PACK_TYPE"0603V"
TOLERANCE"20%"
VALUE"47UF";
"B"
$PN"2"2;
"A"
$PN"1"1;
%"CAP_A"
"1","(2875,1425)","0","dev_discrete","I202";
;
CDS_SEC"1"
SEC_TYPE"0603V"
SEC"1"
CDS_LOCATION"C7M5"
CDS_LIB"dev_discrete"
PART_NUMBER"602433-106"
LOCATION"C7M5"
VALUE"47UF"
TOLERANCE"20%"
VOLTAGE"4V"
MATERIAL"X5R"
PACK_TYPE"0603V";
"B"
$PN"2"2;
"A"
$PN"1"1;
%"CAP_A"
"1","(3275,1425)","0","dev_discrete","I203";
;
SEC"1"
SEC_TYPE"0603V"
CDS_SEC"1"
CDS_LOCATION"C8M10"
CDS_LIB"dev_discrete"
PART_NUMBER"602433-106"
LOCATION"C8M10"
MATERIAL"X5R"
VOLTAGE"4V"
PACK_TYPE"0603V"
TOLERANCE"20%"
VALUE"47UF";
"B"
$PN"2"2;
"A"
$PN"1"1;
%"CAP_A"
"1","(3625,1425)","0","dev_discrete","I204";
;
CDS_SEC"1"
SEC_TYPE"0603V"
SEC"1"
CDS_LOCATION"C2B2"
CDS_LIB"dev_discrete"
LOCATION"C2B2"
PART_NUMBER"602433-106"
VALUE"47UF"
TOLERANCE"20%"
VOLTAGE"4V"
MATERIAL"X5R"
PACK_TYPE"0603V";
"B"
$PN"2"2;
"A"
$PN"1"1;
%"CAP_A"
"1","(3975,1425)","0","dev_discrete","I205";
;
CDS_SEC"1"
SEC_TYPE"0603V"
SEC"1"
CDS_LOCATION"C8M9"
CDS_LIB"dev_discrete"
MATERIAL"X5R"
PACK_TYPE"0603V"
TOLERANCE"20%"
VALUE"47UF"
PART_NUMBER"602433-106"
LOCATION"C8M9"
VOLTAGE"4V";
"B"
$PN"2"2;
"A"
$PN"1"1;
%"CAP_A"
"1","(4375,1425)","0","dev_discrete","I206";
;
SEC"1"
SEC_TYPE"0603V"
CDS_SEC"1"
CDS_LOCATION"C8M2"
CDS_LIB"dev_discrete"
PART_NUMBER"602433-106"
LOCATION"C8M2"
VALUE"47UF"
TOLERANCE"20%"
VOLTAGE"4V"
MATERIAL"X5R"
PACK_TYPE"0603V";
"B"
$PN"2"2;
"A"
$PN"1"1;
%"PVDDQ_KLM"
"1","(-1550,3175)","0","mstr_symbols","I207";
;
HDL_POWER"PVDDQ_KLM"
BODY_TYPE"PLUMBING"
BOM_COST"MEM_VRD_PVPP_AB"
ROOM"VDDQ_KLM_PWR_VR"
VOLTAGE"1.2V"
CDS_LIB"mstr_symbols";
"G\NAC"10;
%"GND"
"1","(-1900,2525)","0","mstr_symbols","I208";
;
HDL_POWER"GND"
BODY_TYPE"PLUMBING"
CDS_LIB"mstr_symbols"
VOLTAGE"0"
SIZE"1B"
BOM_COST"MEM_VRD_PVDDQ_CD"
ROOM"VDDQ_ABC_PWR_VR";
"A\NAC"11;
%"CAP_A"
"1","(2125,-75)","0","dev_discrete","I209";
;
SEC"1"
SEC_TYPE"0603V"
ROOM"PVDDQ_KLM"
CDS_LOCATION"C2A2"
CDS_SEC"1"
CDS_LIB"dev_discrete"
LOCATION"C2A2"
VALUE"22.0UF"
PART_NUMBER"E15431-004"
PACK_TYPE"0603V"
TOLERANCE"20%"
VOLTAGE"4V"
MATERIAL"X6S";
"B"
$PN"2"13;
"A"
$PN"1"12;
%"CAP_A"
"1","(1850,-75)","0","dev_discrete","I210";
;
SEC_TYPE"0603V"
SEC"1"
ROOM"PVDDQ_KLM"
CDS_LOCATION"C2A1"
CDS_SEC"1"
CDS_LIB"dev_discrete"
LOCATION"C2A1"
VALUE"22.0UF"
PART_NUMBER"E15431-004"
MATERIAL"X6S"
VOLTAGE"4V"
TOLERANCE"20%"
PACK_TYPE"0603V";
"B"
$PN"2"13;
"A"
$PN"1"12;
%"CAP_A"
"1","(1550,-75)","0","dev_discrete","I211";
;
SEC_TYPE"0603V"
SEC"1"
ROOM"PVDDQ_KLM"
CDS_LOCATION"C2A12"
CDS_SEC"1"
CDS_LIB"dev_discrete"
LOCATION"C2A12"
VALUE"22.0UF"
PART_NUMBER"E15431-004"
MATERIAL"X6S"
VOLTAGE"4V"
TOLERANCE"20%"
PACK_TYPE"0603V";
"B"
$PN"2"13;
"A"
$PN"1"12;
%"CAP_A"
"1","(1250,-75)","0","dev_discrete","I212";
;
ROOM"PVDDQ_KLM"
SEC"1"
SEC_TYPE"0603V"
CDS_SEC"1"
CDS_LOCATION"C2A13"
CDS_LIB"dev_discrete"
LOCATION"C2A13"
VALUE"22.0UF"
PART_NUMBER"E15431-004"
TOLERANCE"20%"
PACK_TYPE"0603V"
VOLTAGE"4V"
MATERIAL"X6S";
"B"
$PN"2"13;
"A"
$PN"1"12;
%"CAP_A"
"1","(975,-75)","0","dev_discrete","I213";
;
ROOM"PVDDQ_KLM"
SEC"1"
SEC_TYPE"0603V"
CDS_SEC"1"
CDS_LOCATION"C2A11"
CDS_LIB"dev_discrete"
LOCATION"C2A11"
VALUE"22.0UF"
PART_NUMBER"E15431-004"
MATERIAL"X6S"
VOLTAGE"4V"
TOLERANCE"20%"
PACK_TYPE"0603V";
"B"
$PN"2"13;
"A"
$PN"1"12;
%"CAP_A"
"1","(700,-75)","0","dev_discrete","I214";
;
SEC_TYPE"0603V"
SEC"1"
ROOM"PVDDQ_KLM"
CDS_LOCATION"C2A10"
CDS_SEC"1"
CDS_LIB"dev_discrete"
LOCATION"C2A10"
VALUE"22.0UF"
PART_NUMBER"E15431-004"
TOLERANCE"20%"
PACK_TYPE"0603V"
VOLTAGE"4V"
MATERIAL"X6S";
"B"
$PN"2"13;
"A"
$PN"1"12;
%"CAP_A"
"1","(400,-75)","0","dev_discrete","I215";
;
SEC_TYPE"0603V"
SEC"1"
ROOM"PVDDQ_KLM"
CDS_LOCATION"C2A9"
CDS_SEC"1"
CDS_LIB"dev_discrete"
TOLERANCE"20%"
LOCATION"C2A9"
VALUE"22.0UF"
MATERIAL"X6S"
PACK_TYPE"0603V"
PART_NUMBER"E15431-004"
VOLTAGE"4V";
"B"
$PN"2"13;
"A"
$PN"1"12;
%"CAP_A"
"1","(100,-75)","0","dev_discrete","I216";
;
ROOM"PVDDQ_KLM"
CDS_LOCATION"C3A2"
CDS_SEC"1"
SEC_TYPE"0603V"
SEC"1"
CDS_LIB"dev_discrete"
MATERIAL"X6S"
LOCATION"C3A2"
VALUE"22.0UF"
PART_NUMBER"E15431-004"
PACK_TYPE"0603V"
TOLERANCE"20%"
VOLTAGE"4V";
"B"
$PN"2"13;
"A"
$PN"1"12;
%"CAP_A"
"1","(-225,-75)","0","dev_discrete","I217";
;
SEC_TYPE"0603V"
SEC"1"
ROOM"PVDDQ_KLM"
CDS_LOCATION"C3A1"
CDS_SEC"1"
CDS_LIB"dev_discrete"
PART_NUMBER"E15431-004"
LOCATION"C3A1"
VALUE"22.0UF"
TOLERANCE"20%"
VOLTAGE"4V"
MATERIAL"X6S"
PACK_TYPE"0603V";
"B"
$PN"2"13;
"A"
$PN"1"12;
%"CAP_A"
"1","(-500,-75)","0","dev_discrete","I218";
;
ROOM"PVDDQ_KLM"
SEC"1"
SEC_TYPE"0603V"
CDS_SEC"1"
CDS_LOCATION"C2A7"
CDS_LIB"dev_discrete"
LOCATION"C2A7"
VALUE"22.0UF"
PART_NUMBER"E15431-004"
TOLERANCE"20%"
PACK_TYPE"0603V"
VOLTAGE"4V"
MATERIAL"X6S";
"B"
$PN"2"13;
"A"
$PN"1"12;
%"CAP_A"
"1","(-800,-75)","0","dev_discrete","I219";
;
CDS_LOCATION"C2A6"
CDS_SEC"1"
SEC_TYPE"0603V"
SEC"1"
ROOM"PVDDQ_KLM"
CDS_LIB"dev_discrete"
VALUE"22.0UF"
LOCATION"C2A6"
PART_NUMBER"E15431-004"
TOLERANCE"20%"
PACK_TYPE"0603V"
VOLTAGE"4V"
MATERIAL"X6S";
"B"
$PN"2"13;
"A"
$PN"1"12;
%"CAP_A"
"1","(-1100,-75)","0","dev_discrete","I220";
;
SEC_TYPE"0603V"
SEC"1"
ROOM"PVDDQ_KLM"
CDS_LOCATION"C2A14"
CDS_SEC"1"
CDS_LIB"dev_discrete"
VALUE"22.0UF"
LOCATION"C2A14"
MATERIAL"X6S"
VOLTAGE"4V"
PACK_TYPE"0603V"
TOLERANCE"20%"
PART_NUMBER"E15431-004";
"B"
$PN"2"13;
"A"
$PN"1"12;
%"CAP_A"
"1","(-1375,-75)","0","dev_discrete","I221";
;
SEC_TYPE"0603V"
SEC"1"
ROOM"PVDDQ_KLM"
CDS_LOCATION"C2A15"
CDS_SEC"1"
CDS_LIB"dev_discrete"
PACK_TYPE"0603V"
VALUE"22.0UF"
LOCATION"C2A15"
MATERIAL"X6S"
PART_NUMBER"E15431-004"
TOLERANCE"20%"
VOLTAGE"4V";
"B"
$PN"2"13;
"A"
$PN"1"12;
%"CAP_A"
"1","(-1650,-75)","0","dev_discrete","I222";
;
SEC_TYPE"0603V"
SEC"1"
ROOM"PVDDQ_KLM"
CDS_LOCATION"C3A5"
CDS_SEC"1"
CDS_LIB"dev_discrete"
PART_NUMBER"E15431-004"
MATERIAL"X6S"
TOLERANCE"20%"
VALUE"22.0UF"
LOCATION"C3A5"
PACK_TYPE"0603V"
VOLTAGE"4V";
"B"
$PN"2"13;
"A"
$PN"1"12;
%"CAP_A"
"1","(-1950,-75)","0","dev_discrete","I223";
;
ROOM"PVDDQ_KLM"
CDS_LOCATION"C3A6"
CDS_SEC"1"
SEC_TYPE"0603V"
SEC"1"
CDS_LIB"dev_discrete"
PACK_TYPE"0603V"
MATERIAL"X6S"
LOCATION"C3A6"
VALUE"22.0UF"
PART_NUMBER"E15431-004"
TOLERANCE"20%"
VOLTAGE"4V";
"B"
$PN"2"13;
"A"
$PN"1"12;
%"PVDDQ_KLM"
"1","(-2250,175)","0","mstr_symbols","I224";
;
HDL_POWER"PVDDQ_KLM"
BODY_TYPE"PLUMBING"
ROOM"VDDQ_KLM_PWR_VR"
BOM_COST"VDDQ_KLM_PWR_VR"
VOLTAGE"1.2V"
CDS_LIB"mstr_symbols";
"G\NAC"12;
%"CAP_A"
"1","(-2250,-75)","0","dev_discrete","I225";
;
ROOM"PVDDQ_KLM"
SEC_TYPE"0603V"
SEC"1"
CDS_LIB"dev_discrete"
CDS_SEC"1"
CDS_LOCATION"C7L5"
PACK_TYPE"0603V"
MATERIAL"X6S"
VOLTAGE"4V"
TOLERANCE"20%"
PART_NUMBER"E15431-004"
VALUE"22.0UF"
LOCATION"C7L5";
"B"
$PN"2"13;
"A"
$PN"1"12;
%"GND"
"1","(-2250,-350)","0","mstr_symbols","I226";
;
HDL_POWER"GND"
BODY_TYPE"PLUMBING"
SIZE"1B"
VOLTAGE"0"
CDS_LIB"mstr_symbols"
ROOM"VDDQ_ABC_PWR_VR"
BOM_COST"PROC_VRD_VCCIN_CPU0";
"A\NAC"13;
%"CAP_A"
"1","(2150,-775)","0","dev_discrete","I227";
;
ROOM"PVDDQ_KLM"
SEC"1"
SEC_TYPE"0603V"
CDS_LOCATION"C8M3"
CDS_SEC"1"
CDS_LIB"dev_discrete"
PART_NUMBER"E15431-004"
LOCATION"C8M3"
VALUE"22.0UF"
PACK_TYPE"0603V"
VOLTAGE"4V"
MATERIAL"X6S"
TOLERANCE"20%";
"B"
$PN"2"15;
"A"
$PN"1"14;
%"CAP_A"
"1","(1875,-775)","0","dev_discrete","I228";
;
CDS_LOCATION"C8M5"
CDS_SEC"1"
SEC_TYPE"0603V"
SEC"1"
ROOM"PVDDQ_KLM"
CDS_LIB"dev_discrete"
PACK_TYPE"0603V"
VALUE"22.0UF"
PART_NUMBER"E15431-004"
LOCATION"C8M5"
VOLTAGE"4V"
TOLERANCE"20%"
MATERIAL"X6S";
"B"
$PN"2"15;
"A"
$PN"1"14;
%"CAP_A"
"1","(1575,-775)","0","dev_discrete","I229";
;
ROOM"PVDDQ_KLM"
SEC"1"
SEC_TYPE"0603V"
CDS_SEC"1"
CDS_LOCATION"C8L10"
CDS_LIB"dev_discrete"
VALUE"22.0UF"
PART_NUMBER"E15431-004"
LOCATION"C8L10"
VOLTAGE"4V"
MATERIAL"X6S"
PACK_TYPE"0603V"
TOLERANCE"20%";
"B"
$PN"2"15;
"A"
$PN"1"14;
%"CAP_A"
"1","(1275,-775)","0","dev_discrete","I230";
;
ROOM"PVDDQ_KLM"
SEC"1"
SEC_TYPE"0603V"
CDS_SEC"1"
CDS_LOCATION"C2A3"
CDS_LIB"dev_discrete"
PART_NUMBER"E15431-004"
MATERIAL"X6S"
VOLTAGE"4V"
PACK_TYPE"0603V"
TOLERANCE"20%"
VALUE"22.0UF"
LOCATION"C2A3";
"B"
$PN"2"15;
"A"
$PN"1"14;
%"CAP_A"
"1","(1000,-775)","0","dev_discrete","I231";
;
CDS_SEC"1"
CDS_LOCATION"C7M1"
ROOM"PVDDQ_KLM"
SEC_TYPE"0603V"
SEC"1"
CDS_LIB"dev_discrete"
PART_NUMBER"E15431-004"
LOCATION"C7M1"
VALUE"22.0UF"
VOLTAGE"4V"
MATERIAL"X6S"
PACK_TYPE"0603V"
TOLERANCE"20%";
"B"
$PN"2"15;
"A"
$PN"1"14;
%"CAP_A"
"1","(725,-775)","0","dev_discrete","I232";
;
ROOM"PVDDQ_KLM"
SEC_TYPE"0603V"
SEC"1"
CDS_LOCATION"C7M2"
CDS_SEC"1"
CDS_LIB"dev_discrete"
PART_NUMBER"E15431-004"
VALUE"22.0UF"
LOCATION"C7M2"
VOLTAGE"4V"
TOLERANCE"20%"
PACK_TYPE"0603V"
MATERIAL"X6S";
"B"
$PN"2"15;
"A"
$PN"1"14;
%"CAP_A"
"1","(425,-775)","0","dev_discrete","I233";
;
ROOM"PVDDQ_KLM"
CDS_SEC"1"
SEC_TYPE"0603V"
SEC"1"
CDS_LOCATION"C8M4"
CDS_LIB"dev_discrete"
MATERIAL"X6S"
VOLTAGE"4V"
PACK_TYPE"0603V"
TOLERANCE"20%"
VALUE"22.0UF"
PART_NUMBER"E15431-004"
LOCATION"C8M4";
"B"
$PN"2"15;
"A"
$PN"1"14;
%"CAP_A"
"1","(125,-775)","0","dev_discrete","I234";
;
ROOM"PVDDQ_KLM"
SEC_TYPE"0603V"
SEC"1"
CDS_LOCATION"C2A4"
CDS_SEC"1"
CDS_LIB"dev_discrete"
VALUE"22.0UF"
MATERIAL"X6S"
PACK_TYPE"0603V"
TOLERANCE"20%"
PART_NUMBER"E15431-004"
LOCATION"C2A4"
VOLTAGE"4V";
"B"
$PN"2"15;
"A"
$PN"1"14;
%"CAP_A"
"1","(-200,-775)","0","dev_discrete","I235";
;
ROOM"PVDDQ_KLM"
SEC"1"
SEC_TYPE"0603V"
CDS_SEC"1"
CDS_LOCATION"C8M6"
CDS_LIB"dev_discrete"
PACK_TYPE"0603V"
PART_NUMBER"E15431-004"
MATERIAL"X6S"
TOLERANCE"20%"
VALUE"22.0UF"
LOCATION"C8M6"
VOLTAGE"4V";
"B"
$PN"2"15;
"A"
$PN"1"14;
%"CAP_A"
"1","(-475,-775)","0","dev_discrete","I236";
;
ROOM"PVDDQ_KLM"
SEC"1"
SEC_TYPE"0603V"
CDS_SEC"1"
CDS_LOCATION"C8L9"
CDS_LIB"dev_discrete"
VALUE"22.0UF"
PART_NUMBER"E15431-004"
LOCATION"C8L9"
VOLTAGE"4V"
MATERIAL"X6S"
PACK_TYPE"0603V"
TOLERANCE"20%";
"B"
$PN"2"15;
"A"
$PN"1"14;
%"CAP_A"
"1","(-775,-775)","0","dev_discrete","I237";
;
ROOM"PVDDQ_KLM"
SEC"1"
SEC_TYPE"0603V"
CDS_SEC"1"
CDS_LOCATION"C8L8"
CDS_LIB"dev_discrete"
PART_NUMBER"E15431-004"
VALUE"22.0UF"
LOCATION"C8L8"
TOLERANCE"20%"
PACK_TYPE"0603V"
VOLTAGE"4V"
MATERIAL"X6S";
"B"
$PN"2"15;
"A"
$PN"1"14;
%"CAP_A"
"1","(-1075,-775)","0","dev_discrete","I238";
;
ROOM"PVDDQ_KLM"
CDS_SEC"1"
SEC_TYPE"0603V"
SEC"1"
CDS_LOCATION"C7L4"
CDS_LIB"dev_discrete"
MATERIAL"X6S"
VOLTAGE"4V"
PACK_TYPE"0603V"
TOLERANCE"20%"
VALUE"22.0UF"
PART_NUMBER"E15431-004"
LOCATION"C7L4";
"B"
$PN"2"15;
"A"
$PN"1"14;
%"CAP_A"
"1","(-1350,-775)","0","dev_discrete","I239";
;
ROOM"PVDDQ_KLM"
CDS_SEC"1"
SEC_TYPE"0603V"
SEC"1"
CDS_LOCATION"C8L7"
CDS_LIB"dev_discrete"
VOLTAGE"4V"
TOLERANCE"20%"
MATERIAL"X6S"
PART_NUMBER"E15431-004"
PACK_TYPE"0603V"
VALUE"22.0UF"
LOCATION"C8L7";
"B"
$PN"2"15;
"A"
$PN"1"14;
%"CAP_A"
"1","(-1625,-775)","0","dev_discrete","I240";
;
ROOM"PVDDQ_KLM"
CDS_SEC"1"
SEC_TYPE"0603V"
SEC"1"
CDS_LOCATION"C8L6"
CDS_LIB"dev_discrete"
PACK_TYPE"0603V"
MATERIAL"X6S"
VOLTAGE"4V"
TOLERANCE"20%"
VALUE"22.0UF"
PART_NUMBER"E15431-004"
LOCATION"C8L6";
"B"
$PN"2"15;
"A"
$PN"1"14;
%"CAP_A"
"1","(-1925,-775)","0","dev_discrete","I241";
;
ROOM"PVDDQ_KLM"
SEC_TYPE"0603V"
SEC"1"
CDS_LOCATION"C8L5"
CDS_SEC"1"
CDS_LIB"dev_discrete"
PART_NUMBER"E15431-004"
VALUE"22.0UF"
LOCATION"C8L5"
VOLTAGE"4V"
TOLERANCE"20%"
MATERIAL"X6S"
PACK_TYPE"0603V";
"B"
$PN"2"15;
"A"
$PN"1"14;
%"PVDDQ_KLM"
"1","(-2225,-525)","0","mstr_symbols","I242";
;
HDL_POWER"PVDDQ_KLM"
BODY_TYPE"PLUMBING"
BOM_COST"VDDQ_KLM_PWR_VR"
ROOM"VDDQ_KLM_PWR_VR"
CDS_LIB"mstr_symbols"
VOLTAGE"1.2V";
"G\NAC"14;
%"CAP_A"
"1","(-2225,-775)","0","dev_discrete","I243";
;
CDS_LOCATION"C8M1"
CDS_SEC"1"
SEC_TYPE"0603V"
SEC"1"
ROOM"PVDDQ_KLM"
CDS_LIB"dev_discrete"
LOCATION"C8M1"
VALUE"22.0UF"
TOLERANCE"20%"
MATERIAL"X6S"
PART_NUMBER"E15431-004"
PACK_TYPE"0603V"
VOLTAGE"4V";
"B"
$PN"2"15;
"A"
$PN"1"14;
%"GND"
"1","(-2225,-1050)","0","mstr_symbols","I244";
;
HDL_POWER"GND"
BODY_TYPE"PLUMBING"
ROOM"VDDQ_ABC_PWR_VR"
BOM_COST"PROC_VRD_VCCIN_CPU0"
CDS_LIB"mstr_symbols"
VOLTAGE"0"
SIZE"1B";
"A\NAC"15;
%"SHUNT"
"1","(75,2175)","0","mstr_misc","I245";
;
CDS_SEC"1"
CDS_LOCATION"SH7L2"
SEC_TYPE"SH0201"
CDS_LIB"mstr_misc"
PACK_TYPE"SH0201"
PIN_SHORT"A:B"
SEC"1"
MATERIAL"EMPTY"
PART_NUMBER"N_A"
LOCATION"SH7L2";
"A"
$PN"1"22;
"B"
$PN"2"17;
%"SHUNT"
"1","(75,1725)","0","mstr_misc","I246";
;
CDS_SEC"1"
CDS_LOCATION"SH7L1"
SEC_TYPE"SH0201"
CDS_LIB"mstr_misc"
PACK_TYPE"SH0201"
PIN_SHORT"A:B"
SEC"1"
MATERIAL"EMPTY"
PART_NUMBER"N_A"
LOCATION"SH7L1";
"A"
$PN"1"23;
"B"
$PN"2"16;
%"RES"
"2","(4525,-500)","0","mstr_discrete","I58";
;
CDS_SEC"1"
$SEC"1"
BOM_COST"MEM_VRD_PVPP_AB"
CDS_LOCATION"R1A1"
ROOM"VDDQ_KLM_PWR_VR"
CDS_LIB"mstr_discrete"
WATTAGE"1/10W"
MATERIAL"CHIP"
PACK_TYPE"0603"
TOLERANCE"1%"
VALUE"120.0"
PART_NUMBER"G22026-003"
LOCATION"R1A1";
"A"
$PN"1"18;
"B"
$PN"2"19;
%"GND"
"1","(275,1500)","0","mstr_symbols","I65";
;
HDL_POWER"GND"
BODY_TYPE"PLUMBING"
CDS_LIB"mstr_symbols"
VOLTAGE"0"
SIZE"1B"
BOM_COST"MEM_VRD_PVPP_AB"
ROOM"VDDQ_KLM_PWR_VR";
"A\NAC"16;
%"PVDDQ_KLM"
"1","(300,2375)","0","mstr_symbols","I73";
;
HDL_POWER"PVDDQ_KLM"
BODY_TYPE"PLUMBING"
ROOM"VDDQ_KLM_PWR_VR"
BOM_COST"MEM_VRD_PVPP_AB"
CDS_LIB"mstr_symbols"
VOLTAGE"1.2V";
"G\NAC"17;
%"RES"
"2","(-375,1925)","0","mstr_discrete","I74";
;
CDS_SEC"1"
SEC_TYPE"0402"
ROOM"VDDQ_KLM_PWR_VR"
SEC"1"
CDS_LOCATION"R7L2"
CDS_LIB"mstr_discrete"
LOCATION"R7L2"
WATTAGE"1/16W"
PACK_TYPE"0402"
VALUE"100.0"
PART_NUMBER"G21796-017"
MATERIAL"EMPTY"
TOLERANCE"1%";
"A"
$PN"1"22;
"B"
$PN"2"23;
%"CAPP"
"1","(2900,-475)","0","mstr_discrete","I75";
;
CDS_SEC"1"
SEC"1"
SEC_TYPE"3018"
ROOM"VDDQ_KLM_PWR_VR"
CDS_LOCATION"C9L9"
CDS_LIB"mstr_discrete"
VALUE"470UF"
PART_NUMBER"699013-049"
TOLERANCE"20%"
LOCATION"C9L9"
VOLTAGE"2.5V"
MATERIAL"ALUM"
PACK_TYPE"3018";
"B"
$PN"2"19;
"A"
$PN"1"18;
%"CAPP"
"1","(3325,-475)","0","mstr_discrete","I76";
;
CDS_SEC"1"
SEC_TYPE"3018"
SEC"1"
CDS_LOCATION"C9L12"
ROOM"VDDQ_KLM_PWR_VR"
CDS_LIB"mstr_discrete"
PART_NUMBER"699013-049"
LOCATION"C9L12"
VALUE"470UF"
TOLERANCE"20%"
VOLTAGE"2.5V"
MATERIAL"ALUM"
PACK_TYPE"3018";
"B"
$PN"2"19;
"A"
$PN"1"18;
%"CAPP"
"1","(3750,-475)","0","mstr_discrete","I77";
;
CDS_SEC"1"
SEC"1"
SEC_TYPE"3018"
ROOM"VDDQ_KLM_PWR_VR"
CDS_LOCATION"C9L4"
CDS_LIB"mstr_discrete"
TOLERANCE"20%"
VALUE"470UF"
LOCATION"C9L4"
VOLTAGE"2.5V"
MATERIAL"ALUM"
PACK_TYPE"3018"
PART_NUMBER"699013-049";
"B"
$PN"2"19;
"A"
$PN"1"18;
%"CAPP"
"1","(4150,-500)","0","mstr_discrete","I78";
;
CDS_SEC"1"
SEC"1"
SEC_TYPE"3018"
ROOM"VDDQ_KLM_PWR_VR"
CDS_LOCATION"C9L2"
CDS_LIB"mstr_discrete"
TOLERANCE"20%"
VALUE"470UF"
LOCATION"C9L2"
PART_NUMBER"699013-049"
PACK_TYPE"3018"
VOLTAGE"2.5V"
MATERIAL"ALUM";
"B"
$PN"2"19;
"A"
$PN"1"18;
%"PVDDQ_KLM"
"1","(2900,-175)","0","mstr_symbols","I80";
;
HDL_POWER"PVDDQ_KLM"
BODY_TYPE"PLUMBING"
ROOM"VDDQ_KLM_PWR_VR"
CDS_LIB"mstr_symbols"
BOM_COST"MEM_VRD_PVPP_AB"
VOLTAGE"1.2V";
"G\NAC"18;
%"GND"
"1","(2900,-900)","0","mstr_symbols","I81";
;
HDL_POWER"GND"
BODY_TYPE"PLUMBING"
CDS_LIB"mstr_symbols"
SIZE"1B"
VOLTAGE"0"
BOM_COST"MEM_VRD_PVPP_AB";
"A\NAC"19;
%"CAP"
"1","(5000,2825)","0","mstr_discrete","I82";
;
CDS_SEC"1"
ROOM"VDDQ_KLM_PWR_VR"
SEC_TYPE"0805"
BOM_COST"MEM_VRD_PVDDQ_CD"
SEC"1"
CDS_LOCATION"C2A8"
CDS_LIB"mstr_discrete"
MATERIAL"X5R"
PACK_TYPE"0805"
TOLERANCE"20%"
VALUE"100UF"
PART_NUMBER"602433-112"
LOCATION"C2A8"
VOLTAGE"4V";
"A"
$PN"1"20;
"B"
$PN"2"21;
%"CAP"
"1","(4600,2825)","0","mstr_discrete","I83";
;
CDS_SEC"1"
ROOM"VDDQ_KLM_PWR_VR"
CDS_LOCATION"C8L2"
SEC"1"
SEC_TYPE"0805"
BOM_COST"MEM_VRD_PVDDQ_CD"
CDS_LIB"mstr_discrete"
PART_NUMBER"602433-112"
MATERIAL"X5R"
VOLTAGE"4V"
PACK_TYPE"0805"
TOLERANCE"20%"
VALUE"100UF"
LOCATION"C8L2";
"A"
$PN"1"20;
"B"
$PN"2"21;
%"CAP"
"1","(4250,2825)","0","mstr_discrete","I88";
;
CDS_SEC"1"
ROOM"VDDQ_KLM_PWR_VR"
BOM_COST"MEM_VRD_PVDDQ_CD"
SEC_TYPE"0805"
SEC"1"
CDS_LOCATION"C8L11"
CDS_LIB"mstr_discrete"
MATERIAL"X5R"
VOLTAGE"4V"
PACK_TYPE"0805"
TOLERANCE"20%"
VALUE"100UF"
PART_NUMBER"602433-112"
LOCATION"C8L11";
"A"
$PN"1"20;
"B"
$PN"2"21;
%"CAP"
"1","(3850,2825)","0","mstr_discrete","I89";
;
CDS_SEC"1"
ROOM"VDDQ_KLM_PWR_VR"
SEC"1"
BOM_COST"MEM_VRD_PVDDQ_CD"
SEC_TYPE"0805"
CDS_LOCATION"C2A16"
CDS_LIB"mstr_discrete"
PART_NUMBER"602433-112"
VALUE"100UF"
LOCATION"C2A16"
VOLTAGE"4V"
TOLERANCE"20%"
PACK_TYPE"0805"
MATERIAL"X5R";
"A"
$PN"1"20;
"B"
$PN"2"21;
%"CAP"
"1","(3500,2825)","0","mstr_discrete","I90";
;
CDS_SEC"1"
ROOM"VDDQ_KLM_PWR_VR"
SEC_TYPE"0805"
BOM_COST"MEM_VRD_PVDDQ_CD"
SEC"1"
CDS_LOCATION"C8M7"
CDS_LIB"mstr_discrete"
MATERIAL"X5R"
VOLTAGE"4V"
PACK_TYPE"0805"
TOLERANCE"20%"
VALUE"100UF"
PART_NUMBER"602433-112"
LOCATION"C8M7";
"A"
$PN"1"20;
"B"
$PN"2"21;
%"CAP"
"1","(3150,2825)","0","mstr_discrete","I91";
;
CDS_SEC"1"
SEC_TYPE"0805"
BOM_COST"MEM_VRD_PVDDQ_CD"
SEC"1"
CDS_LOCATION"C8M11"
ROOM"VDDQ_KLM_PWR_VR"
CDS_LIB"mstr_discrete"
VALUE"100UF"
PART_NUMBER"602433-112"
LOCATION"C8M11"
VOLTAGE"4V"
TOLERANCE"20%"
PACK_TYPE"0805"
MATERIAL"X5R";
"A"
$PN"1"20;
"B"
$PN"2"21;
%"CAP"
"1","(2750,2825)","0","mstr_discrete","I92";
;
CDS_SEC"1"
ROOM"VDDQ_KLM_PWR_VR"
SEC_TYPE"0805"
BOM_COST"MEM_VRD_PVDDQ_CD"
SEC"1"
CDS_LOCATION"C7L1"
CDS_LIB"mstr_discrete"
PART_NUMBER"602433-112"
MATERIAL"X5R"
VOLTAGE"4V"
PACK_TYPE"0805"
TOLERANCE"20%"
VALUE"100UF"
LOCATION"C7L1";
"A"
$PN"1"20;
"B"
$PN"2"21;
%"PVDDQ_KLM"
"1","(2400,3100)","0","mstr_symbols","I93";
;
HDL_POWER"PVDDQ_KLM"
BODY_TYPE"PLUMBING"
ROOM"VDDQ_KLM_PWR_VR"
CDS_LIB"mstr_symbols"
BOM_COST"MEM_VRD_PVDDQ_CD"
VOLTAGE"1.2V";
"G\NAC"20;
%"GND"
"1","(4125,2450)","0","mstr_symbols","I94";
;
HDL_POWER"GND"
BODY_TYPE"PLUMBING"
CDS_LIB"mstr_symbols"
SIZE"1B"
VOLTAGE"0"
BOM_COST"MEM_VRD_PVDDQ_CD"
ROOM"VDDQ_KLM_PWR_VR";
"A\NAC"21;
END.
